(kicad_pcb
	(version 20260206)
	(generator "pcbnew")
	(generator_version "10.0")
	(general
		(thickness 1.6)
		(legacy_teardrops no)
	)
	(paper "A4")
	(title_block
		(title "Bryce Canyon_SCC_16316-1_OCP.brd")
		(comment 1 "Bryce Canyon / footprints 1407-1414 of 1561")
	)
	(layers
		(0 "F.Cu" signal "TOP")
		(4 "In1.Cu" signal "L2GND")
		(6 "In2.Cu" signal "L3")
		(8 "In3.Cu" signal "L4VCC")
		(10 "In4.Cu" signal "L5VCC")
		(12 "In5.Cu" signal "L6")
		(14 "In6.Cu" signal "L7GND")
		(2 "B.Cu" signal "BOTTOM")
		(9 "F.Adhes" user "F.Adhesive")
		(11 "B.Adhes" user "B.Adhesive")
		(13 "F.Paste" user "Package Geometry/Pastemask Top")
		(15 "B.Paste" user "Package Geometry/Pastemask Bottom")
		(5 "F.SilkS" user "Ref Des/Silkscreen Top")
		(7 "B.SilkS" user "Ref Des/Silkscreen Bottom")
		(1 "F.Mask" user "Board Geometry/Soldermask Top")
		(3 "B.Mask" user "Board Geometry/Soldermask Bottom")
		(17 "Dwgs.User" user "User.Drawings")
		(19 "Cmts.User" user "User.Comments")
		(21 "Eco1.User" user "User.Eco1")
		(23 "Eco2.User" user "User.Eco2")
		(25 "Edge.Cuts" user "Board Geometry/Outline")
		(27 "Margin" user)
		(31 "F.CrtYd" user "Package Geometry/Place Bound Top")
		(29 "B.CrtYd" user "Package Geometry/Place Bound Bottom")
		(35 "F.Fab" user "Ref Des/Assembly Top")
		(33 "B.Fab" user "Ref Des/Assembly Bottom")
	)
	(footprint ""
		(layer "B.Cu")
		(at 158.502604 -66.916808 180)
		(property "Reference" "L21"
			(at 0 0 0)
			(layer "B.SilkS")
			(hide yes)
			(effects
				(font
					(size 1.27 1.27)
				)
				(justify mirror)
			)
		)
		(property "Value" "MPZ2012S601AT-GP"
			(at 0 -4.2418 180)
			(unlocked yes)
			(layer "B.Fab")
			(hide yes)
			(effects
				(font
					(size 1.016 1.016)
					(thickness 0.1524)
				)
				(justify mirror)
			)
		)
		(property "Device Type" "L805H42"
			(at 0 -5.7912 180)
			(unlocked yes)
			(layer "B.Fab")
			(hide yes)
			(effects
				(font
					(size 1.016 1.016)
					(thickness 0.1524)
				)
				(justify mirror)
			)
		)
		(duplicate_pad_numbers_are_jumpers no)
		(fp_line
			(start 0.889 1.7018)
			(end 0.889 -1.7018)
			(stroke
				(width 0.1524)
				(type default)
			)
			(layer "B.SilkS")
		)
		(fp_line
			(start 0.889 -1.7018)
			(end -0.889 -1.7018)
			(stroke
				(width 0.1524)
				(type default)
			)
			(layer "B.SilkS")
		)
		(fp_line
			(start -0.889 1.7018)
			(end 0.889 1.7018)
			(stroke
				(width 0.1524)
				(type default)
			)
			(layer "B.SilkS")
		)
		(fp_line
			(start -0.889 -1.7018)
			(end -0.889 1.7018)
			(stroke
				(width 0.1524)
				(type default)
			)
			(layer "B.SilkS")
		)
		(fp_rect
			(start 0.9652 1.778)
			(end -0.9652 -1.778)
			(stroke
				(width 0)
				(type default)
			)
			(fill no)
			(layer "B.CrtYd")
		)
		(fp_rect
			(start 0.9652 1.778)
			(end -0.9652 -1.778)
			(stroke
				(width 0)
				(type default)
			)
			(fill no)
			(layer "B.Fab")
		)
		(pad "1" smd rect
			(at 0 -0.9652)
			(size 1.397 1.143)
			(layers "B.Cu" "B.Mask" "B.Paste")
			(net "SHELL_PLL_VDD")
		)
		(pad "2" smd rect
			(at 0 0.9652)
			(size 1.397 1.143)
			(layers "B.Cu" "B.Mask" "B.Paste")
			(net "P1V8_C")
		)
	)
	(footprint ""
		(layer "B.Cu")
		(at 121.92 -94.4372 -90)
		(property "Reference" "R557"
			(at 0 0 90)
			(layer "B.SilkS")
			(hide yes)
			(effects
				(font
					(size 1.27 1.27)
				)
				(justify mirror)
			)
		)
		(property "Value" "10KR2F-2-GP"
			(at -0.064008 -3.993896 270)
			(unlocked yes)
			(layer "B.Fab")
			(hide yes)
			(effects
				(font
					(size 1.016 1.016)
					(thickness 0.1524)
				)
				(justify mirror)
			)
		)
		(property "Device Type" "R402H16"
			(at -0.064008 -5.517896 270)
			(unlocked yes)
			(layer "B.Fab")
			(hide yes)
			(effects
				(font
					(size 1.016 1.016)
					(thickness 0.1524)
				)
				(justify mirror)
			)
		)
		(duplicate_pad_numbers_are_jumpers no)
		(fp_line
			(start -0.508 -0.9398)
			(end 0.508 -0.9398)
			(stroke
				(width 0.1524)
				(type default)
			)
			(layer "B.SilkS")
		)
		(fp_line
			(start 0.508 -0.9398)
			(end 0.508 0.9398)
			(stroke
				(width 0.1524)
				(type default)
			)
			(layer "B.SilkS")
		)
		(fp_rect
			(start 0.508 0.9398)
			(end -0.508 -0.9398)
			(stroke
				(width 0)
				(type default)
			)
			(fill no)
			(layer "B.CrtYd")
		)
		(fp_rect
			(start 0.508 0.9398)
			(end -0.508 -0.9398)
			(stroke
				(width 0)
				(type default)
			)
			(fill no)
			(layer "B.Fab")
		)
		(pad "1" smd custom
			(at 0 -0.4445 90)
			(size 0.1397 0.1397)
			(layers "B.Cu" "B.Mask" "B.Paste")
			(net "DRIVE_INSERT_ALERT_LS_N")
			(options
				(clearance outline)
				(anchor circle)
			)
			(primitives
				(gr_poly
					(pts
						(arc
							(start -0.1778 0.2794)
							(mid -0.249642 0.249642)
							(end -0.2794 0.1778)
						)
						(arc
							(start -0.2794 -0.1778)
							(mid -0.249642 -0.249642)
							(end -0.1778 -0.2794)
						)
						(arc
							(start 0.1778 -0.2794)
							(mid 0.249642 -0.249642)
							(end 0.2794 -0.1778)
						)
						(arc
							(start 0.2794 0.1778)
							(mid 0.249642 0.249642)
							(end 0.1778 0.2794)
						)
					)
					(width 0)
					(fill yes)
				)
			)
		)
		(pad "2" smd custom
			(at 0 0.4445 90)
			(size 0.1397 0.1397)
			(layers "B.Cu" "B.Mask" "B.Paste")
			(net "P1V8_E")
			(options
				(clearance outline)
				(anchor circle)
			)
			(primitives
				(gr_poly
					(pts
						(arc
							(start -0.1778 0.2794)
							(mid -0.249642 0.249642)
							(end -0.2794 0.1778)
						)
						(arc
							(start -0.2794 -0.1778)
							(mid -0.249642 -0.249642)
							(end -0.1778 -0.2794)
						)
						(arc
							(start 0.1778 -0.2794)
							(mid 0.249642 -0.249642)
							(end 0.2794 -0.1778)
						)
						(arc
							(start 0.2794 0.1778)
							(mid 0.249642 0.249642)
							(end 0.1778 0.2794)
						)
					)
					(width 0)
					(fill yes)
				)
			)
		)
	)
	(footprint ""
		(layer "B.Cu")
		(at 112.4458 -44.2214 180)
		(property "Reference" "C67"
			(at 0 0 0)
			(layer "B.SilkS")
			(hide yes)
			(effects
				(font
					(size 1.27 1.27)
				)
				(justify mirror)
			)
		)
		(property "Value" "SCD01U16V1KX-GP"
			(at 2.8321 -1.7399 180)
			(unlocked yes)
			(layer "B.Fab")
			(hide yes)
			(effects
				(font
					(size 1.016 1.016)
					(thickness 0.1524)
				)
				(justify mirror)
			)
		)
		(property "Device Type" "C0201H13"
			(at 2.8321 -3.2639 180)
			(unlocked yes)
			(layer "B.Fab")
			(hide yes)
			(effects
				(font
					(size 1.016 1.016)
					(thickness 0.1524)
				)
				(justify mirror)
			)
		)
		(duplicate_pad_numbers_are_jumpers no)
		(fp_rect
			(start 0.2794 0.6477)
			(end -0.2794 -0.6477)
			(stroke
				(width 0)
				(type default)
			)
			(fill no)
			(layer "B.CrtYd")
		)
		(fp_rect
			(start 0.2794 0.6477)
			(end -0.2794 -0.6477)
			(stroke
				(width 0)
				(type default)
			)
			(fill no)
			(layer "B.Fab")
		)
		(pad "1" smd custom
			(at 0 -0.2794)
			(size 0.0762 0.0762)
			(layers "B.Cu" "B.Mask" "B.Paste")
			(net "PHY_DPB_TO_SCC_26_DP")
			(options
				(clearance outline)
				(anchor circle)
			)
			(primitives
				(gr_poly
					(pts
						(arc
							(start 0.1524 0.127)
							(mid 0.137521 0.162921)
							(end 0.1016 0.1778)
						)
						(arc
							(start -0.1016 0.1778)
							(mid -0.137521 0.162921)
							(end -0.1524 0.127)
						)
						(arc
							(start -0.1524 -0.127)
							(mid -0.137521 -0.162921)
							(end -0.1016 -0.1778)
						)
						(arc
							(start 0.1016 -0.1778)
							(mid 0.137521 -0.162921)
							(end 0.1524 -0.127)
						)
					)
					(width 0)
					(fill yes)
				)
			)
		)
		(pad "2" smd custom
			(at 0 0.2794)
			(size 0.0762 0.0762)
			(layers "B.Cu" "B.Mask" "B.Paste")
			(net "PHY_DPB_TO_SCC_C_26_DP")
			(options
				(clearance outline)
				(anchor circle)
			)
			(primitives
				(gr_poly
					(pts
						(arc
							(start 0.1524 0.127)
							(mid 0.137521 0.162921)
							(end 0.1016 0.1778)
						)
						(arc
							(start -0.1016 0.1778)
							(mid -0.137521 0.162921)
							(end -0.1524 0.127)
						)
						(arc
							(start -0.1524 -0.127)
							(mid -0.137521 -0.162921)
							(end -0.1016 -0.1778)
						)
						(arc
							(start 0.1016 -0.1778)
							(mid 0.137521 -0.162921)
							(end 0.1524 -0.127)
						)
					)
					(width 0)
					(fill yes)
				)
			)
		)
	)
	(footprint ""
		(layer "B.Cu")
		(at 176.324768 -35.636962)
		(property "Reference" "C426"
			(at 0 0 0)
			(layer "B.SilkS")
			(hide yes)
			(effects
				(font
					(size 1.27 1.27)
				)
				(justify mirror)
			)
		)
		(property "Value" "SCD1U6D3V1KX-GP"
			(at 2.8321 -1.7399 0)
			(unlocked yes)
			(layer "B.Fab")
			(hide yes)
			(effects
				(font
					(size 1.016 1.016)
					(thickness 0.1524)
				)
				(justify mirror)
			)
		)
		(property "Device Type" "C0201H13"
			(at 2.8321 -3.2639 0)
			(unlocked yes)
			(layer "B.Fab")
			(hide yes)
			(effects
				(font
					(size 1.016 1.016)
					(thickness 0.1524)
				)
				(justify mirror)
			)
		)
		(duplicate_pad_numbers_are_jumpers no)
		(fp_rect
			(start 0.2794 0.6477)
			(end -0.2794 -0.6477)
			(stroke
				(width 0)
				(type default)
			)
			(fill no)
			(layer "B.CrtYd")
		)
		(fp_rect
			(start 0.2794 0.6477)
			(end -0.2794 -0.6477)
			(stroke
				(width 0)
				(type default)
			)
			(fill no)
			(layer "B.Fab")
		)
		(pad "1" smd custom
			(at 0 -0.2794 180)
			(size 0.0762 0.0762)
			(layers "B.Cu" "B.Mask" "B.Paste")
			(net "P0V975")
			(options
				(clearance outline)
				(anchor circle)
			)
			(primitives
				(gr_poly
					(pts
						(arc
							(start 0.1524 0.127)
							(mid 0.137521 0.162921)
							(end 0.1016 0.1778)
						)
						(arc
							(start -0.1016 0.1778)
							(mid -0.137521 0.162921)
							(end -0.1524 0.127)
						)
						(arc
							(start -0.1524 -0.127)
							(mid -0.137521 -0.162921)
							(end -0.1016 -0.1778)
						)
						(arc
							(start 0.1016 -0.1778)
							(mid 0.137521 -0.162921)
							(end 0.1524 -0.127)
						)
					)
					(width 0)
					(fill yes)
				)
			)
		)
		(pad "2" smd custom
			(at 0 0.2794 180)
			(size 0.0762 0.0762)
			(layers "B.Cu" "B.Mask" "B.Paste")
			(net "GND")
			(options
				(clearance outline)
				(anchor circle)
			)
			(primitives
				(gr_poly
					(pts
						(arc
							(start 0.1524 0.127)
							(mid 0.137521 0.162921)
							(end 0.1016 0.1778)
						)
						(arc
							(start -0.1016 0.1778)
							(mid -0.137521 0.162921)
							(end -0.1524 0.127)
						)
						(arc
							(start -0.1524 -0.127)
							(mid -0.137521 -0.162921)
							(end -0.1016 -0.1778)
						)
						(arc
							(start 0.1016 -0.1778)
							(mid 0.137521 -0.162921)
							(end 0.1524 -0.127)
						)
					)
					(width 0)
					(fill yes)
				)
			)
		)
	)
	(footprint ""
		(layer "B.Cu")
		(at 128.8034 -40.8686 180)
		(property "Reference" "C31"
			(at 0 0 0)
			(layer "B.SilkS")
			(hide yes)
			(effects
				(font
					(size 1.27 1.27)
				)
				(justify mirror)
			)
		)
		(property "Value" "SCD01U16V1KX-GP"
			(at 2.8321 -1.7399 180)
			(unlocked yes)
			(layer "B.Fab")
			(hide yes)
			(effects
				(font
					(size 1.016 1.016)
					(thickness 0.1524)
				)
				(justify mirror)
			)
		)
		(property "Device Type" "C0201H13"
			(at 2.8321 -3.2639 180)
			(unlocked yes)
			(layer "B.Fab")
			(hide yes)
			(effects
				(font
					(size 1.016 1.016)
					(thickness 0.1524)
				)
				(justify mirror)
			)
		)
		(duplicate_pad_numbers_are_jumpers no)
		(fp_rect
			(start 0.2794 0.6477)
			(end -0.2794 -0.6477)
			(stroke
				(width 0)
				(type default)
			)
			(fill no)
			(layer "B.CrtYd")
		)
		(fp_rect
			(start 0.2794 0.6477)
			(end -0.2794 -0.6477)
			(stroke
				(width 0)
				(type default)
			)
			(fill no)
			(layer "B.Fab")
		)
		(pad "1" smd custom
			(at 0 -0.2794)
			(size 0.0762 0.0762)
			(layers "B.Cu" "B.Mask" "B.Paste")
			(net "PHY_DPB_TO_SCC_28_DP")
			(options
				(clearance outline)
				(anchor circle)
			)
			(primitives
				(gr_poly
					(pts
						(arc
							(start 0.1524 0.127)
							(mid 0.137521 0.162921)
							(end 0.1016 0.1778)
						)
						(arc
							(start -0.1016 0.1778)
							(mid -0.137521 0.162921)
							(end -0.1524 0.127)
						)
						(arc
							(start -0.1524 -0.127)
							(mid -0.137521 -0.162921)
							(end -0.1016 -0.1778)
						)
						(arc
							(start 0.1016 -0.1778)
							(mid 0.137521 -0.162921)
							(end 0.1524 -0.127)
						)
					)
					(width 0)
					(fill yes)
				)
			)
		)
		(pad "2" smd custom
			(at 0 0.2794)
			(size 0.0762 0.0762)
			(layers "B.Cu" "B.Mask" "B.Paste")
			(net "PHY_DPB_TO_SCC_C_28_DP")
			(options
				(clearance outline)
				(anchor circle)
			)
			(primitives
				(gr_poly
					(pts
						(arc
							(start 0.1524 0.127)
							(mid 0.137521 0.162921)
							(end 0.1016 0.1778)
						)
						(arc
							(start -0.1016 0.1778)
							(mid -0.137521 0.162921)
							(end -0.1524 0.127)
						)
						(arc
							(start -0.1524 -0.127)
							(mid -0.137521 -0.162921)
							(end -0.1016 -0.1778)
						)
						(arc
							(start 0.1016 -0.1778)
							(mid 0.137521 -0.162921)
							(end 0.1524 -0.127)
						)
					)
					(width 0)
					(fill yes)
				)
			)
		)
	)
	(footprint ""
		(layer "B.Cu")
		(at 113.284 -68.6562)
		(property "Reference" "C165"
			(at 0 0 0)
			(layer "B.SilkS")
			(hide yes)
			(effects
				(font
					(size 1.27 1.27)
				)
				(justify mirror)
			)
		)
		(property "Value" "SCD1U6D3V1KX-GP"
			(at 2.8321 -1.7399 0)
			(unlocked yes)
			(layer "B.Fab")
			(hide yes)
			(effects
				(font
					(size 1.016 1.016)
					(thickness 0.1524)
				)
				(justify mirror)
			)
		)
		(property "Device Type" "C0201H13"
			(at 2.8321 -3.2639 0)
			(unlocked yes)
			(layer "B.Fab")
			(hide yes)
			(effects
				(font
					(size 1.016 1.016)
					(thickness 0.1524)
				)
				(justify mirror)
			)
		)
		(duplicate_pad_numbers_are_jumpers no)
		(fp_rect
			(start 0.2794 0.6477)
			(end -0.2794 -0.6477)
			(stroke
				(width 0)
				(type default)
			)
			(fill no)
			(layer "B.CrtYd")
		)
		(fp_rect
			(start 0.2794 0.6477)
			(end -0.2794 -0.6477)
			(stroke
				(width 0)
				(type default)
			)
			(fill no)
			(layer "B.Fab")
		)
		(pad "1" smd custom
			(at 0 -0.2794 180)
			(size 0.0762 0.0762)
			(layers "B.Cu" "B.Mask" "B.Paste")
			(net "P0V9")
			(options
				(clearance outline)
				(anchor circle)
			)
			(primitives
				(gr_poly
					(pts
						(arc
							(start 0.1524 0.127)
							(mid 0.137521 0.162921)
							(end 0.1016 0.1778)
						)
						(arc
							(start -0.1016 0.1778)
							(mid -0.137521 0.162921)
							(end -0.1524 0.127)
						)
						(arc
							(start -0.1524 -0.127)
							(mid -0.137521 -0.162921)
							(end -0.1016 -0.1778)
						)
						(arc
							(start 0.1016 -0.1778)
							(mid 0.137521 -0.162921)
							(end 0.1524 -0.127)
						)
					)
					(width 0)
					(fill yes)
				)
			)
		)
		(pad "2" smd custom
			(at 0 0.2794 180)
			(size 0.0762 0.0762)
			(layers "B.Cu" "B.Mask" "B.Paste")
			(net "GND")
			(options
				(clearance outline)
				(anchor circle)
			)
			(primitives
				(gr_poly
					(pts
						(arc
							(start 0.1524 0.127)
							(mid 0.137521 0.162921)
							(end 0.1016 0.1778)
						)
						(arc
							(start -0.1016 0.1778)
							(mid -0.137521 0.162921)
							(end -0.1524 0.127)
						)
						(arc
							(start -0.1524 -0.127)
							(mid -0.137521 -0.162921)
							(end -0.1016 -0.1778)
						)
						(arc
							(start 0.1016 -0.1778)
							(mid 0.137521 -0.162921)
							(end 0.1524 -0.127)
						)
					)
					(width 0)
					(fill yes)
				)
			)
		)
	)
	(footprint ""
		(layer "B.Cu")
		(at 120.4976 -66.675 -90)
		(property "Reference" "C216"
			(at 0 0 90)
			(layer "B.SilkS")
			(hide yes)
			(effects
				(font
					(size 1.27 1.27)
				)
				(justify mirror)
			)
		)
		(property "Value" "SCD1U16V2KX-3GP"
			(at -1.1811 -2.7051 270)
			(unlocked yes)
			(layer "B.Fab")
			(hide yes)
			(effects
				(font
					(size 1.016 1.016)
					(thickness 0.1524)
				)
				(justify mirror)
			)
		)
		(property "Device Type" "C402H22"
			(at -1.1811 -4.2291 270)
			(unlocked yes)
			(layer "B.Fab")
			(hide yes)
			(effects
				(font
					(size 1.016 1.016)
					(thickness 0.1524)
				)
				(justify mirror)
			)
		)
		(duplicate_pad_numbers_are_jumpers no)
		(fp_rect
			(start 0.4318 0.9525)
			(end -0.4318 -0.9525)
			(stroke
				(width 0)
				(type default)
			)
			(fill no)
			(layer "B.CrtYd")
		)
		(fp_rect
			(start 0.4318 0.9525)
			(end -0.4318 -0.9525)
			(stroke
				(width 0)
				(type default)
			)
			(fill no)
			(layer "B.Fab")
		)
		(pad "1" smd custom
			(at 0 -0.4445 90)
			(size 0.1524 0.1524)
			(layers "B.Cu" "B.Mask" "B.Paste")
			(net "GB_VDDH")
			(options
				(clearance outline)
				(anchor circle)
			)
			(primitives
				(gr_poly
					(pts
						(arc
							(start 0.3048 0.2032)
							(mid 0.275042 0.275042)
							(end 0.2032 0.3048)
						)
						(arc
							(start -0.2032 0.3048)
							(mid -0.275042 0.275042)
							(end -0.3048 0.2032)
						)
						(arc
							(start -0.3048 -0.2032)
							(mid -0.275042 -0.275042)
							(end -0.2032 -0.3048)
						)
						(arc
							(start 0.2032 -0.3048)
							(mid 0.275042 -0.275042)
							(end 0.3048 -0.2032)
						)
					)
					(width 0)
					(fill yes)
				)
			)
		)
		(pad "2" smd custom
			(at 0 0.4445 90)
			(size 0.1524 0.1524)
			(layers "B.Cu" "B.Mask" "B.Paste")
			(net "GND")
			(options
				(clearance outline)
				(anchor circle)
			)
			(primitives
				(gr_poly
					(pts
						(arc
							(start 0.3048 0.2032)
							(mid 0.275042 0.275042)
							(end 0.2032 0.3048)
						)
						(arc
							(start -0.2032 0.3048)
							(mid -0.275042 0.275042)
							(end -0.3048 0.2032)
						)
						(arc
							(start -0.3048 -0.2032)
							(mid -0.275042 -0.275042)
							(end -0.2032 -0.3048)
						)
						(arc
							(start 0.2032 -0.3048)
							(mid 0.275042 -0.275042)
							(end 0.3048 -0.2032)
						)
					)
					(width 0)
					(fill yes)
				)
			)
		)
	)
	(footprint ""
		(layer "B.Cu")
		(at 103.3018 -44.2214 180)
		(property "Reference" "C79"
			(at 0 0 0)
			(layer "B.SilkS")
			(hide yes)
			(effects
				(font
					(size 1.27 1.27)
				)
				(justify mirror)
			)
		)
		(property "Value" "SCD01U16V1KX-GP"
			(at 2.8321 -1.7399 180)
			(unlocked yes)
			(layer "B.Fab")
			(hide yes)
			(effects
				(font
					(size 1.016 1.016)
					(thickness 0.1524)
				)
				(justify mirror)
			)
		)
		(property "Device Type" "C0201H13"
			(at 2.8321 -3.2639 180)
			(unlocked yes)
			(layer "B.Fab")
			(hide yes)
			(effects
				(font
					(size 1.016 1.016)
					(thickness 0.1524)
				)
				(justify mirror)
			)
		)
		(duplicate_pad_numbers_are_jumpers no)
		(fp_rect
			(start 0.2794 0.6477)
			(end -0.2794 -0.6477)
			(stroke
				(width 0)
				(type default)
			)
			(fill no)
			(layer "B.CrtYd")
		)
		(fp_rect
			(start 0.2794 0.6477)
			(end -0.2794 -0.6477)
			(stroke
				(width 0)
				(type default)
			)
			(fill no)
			(layer "B.Fab")
		)
		(pad "1" smd custom
			(at 0 -0.2794)
			(size 0.0762 0.0762)
			(layers "B.Cu" "B.Mask" "B.Paste")
			(net "PHY_DPB_TO_SCC_20_DP")
			(options
				(clearance outline)
				(anchor circle)
			)
			(primitives
				(gr_poly
					(pts
						(arc
							(start 0.1524 0.127)
							(mid 0.137521 0.162921)
							(end 0.1016 0.1778)
						)
						(arc
							(start -0.1016 0.1778)
							(mid -0.137521 0.162921)
							(end -0.1524 0.127)
						)
						(arc
							(start -0.1524 -0.127)
							(mid -0.137521 -0.162921)
							(end -0.1016 -0.1778)
						)
						(arc
							(start 0.1016 -0.1778)
							(mid 0.137521 -0.162921)
							(end 0.1524 -0.127)
						)
					)
					(width 0)
					(fill yes)
				)
			)
		)
		(pad "2" smd custom
			(at 0 0.2794)
			(size 0.0762 0.0762)
			(layers "B.Cu" "B.Mask" "B.Paste")
			(net "PHY_DPB_TO_SCC_C_20_DP")
			(options
				(clearance outline)
				(anchor circle)
			)
			(primitives
				(gr_poly
					(pts
						(arc
							(start 0.1524 0.127)
							(mid 0.137521 0.162921)
							(end 0.1016 0.1778)
						)
						(arc
							(start -0.1016 0.1778)
							(mid -0.137521 0.162921)
							(end -0.1524 0.127)
						)
						(arc
							(start -0.1524 -0.127)
							(mid -0.137521 -0.162921)
							(end -0.1016 -0.1778)
						)
						(arc
							(start 0.1016 -0.1778)
							(mid 0.137521 -0.162921)
							(end 0.1524 -0.127)
						)
					)
					(width 0)
					(fill yes)
				)
			)
		)
	)
)
